FILE_TYPE = CONNECTIVITY;
{Allegro Design Entry HDL 17.2-2016 S081 (4005846) 1/11/2022}
"PAGE_NUMBER" = 145;
0"NC";
1"P3V3_AUX\g";
2"P3V3_AUX\g";
3"P3V3_AUX\g";
4"P3V3_AUX\g";
5"P3V3_AUX\g";
6"P3V3_AUX\g";
7"P3V3_AUX\g";
8"P3V3_AUX\g";
9"P3V3_AUX\g";
10"P3V3_AUX\g";
11"P3V3_AUX\g";
12"P3V3_AUX\g";
13"P3V3_AUX\g";
14"P3V3_AUX\g";
15"P3V3_AUX\g";
16"P3V3_AUX\g";
17"P3V3_AUX\g";
18"P3V3_AUX\g";
19"P3V3_AUX\g";
20"P3V3_AUX\g";
21"P3V3_AUX\g";
22"P3V3_AUX\g";
23"P3V3_AUX\g";
24"P3V3_AUX\g";
25"GND\g";
26"GND\g";
27"GND\g";
28"GND\g";
29"GND\g";
30"GND\g";
31"GND\g";
32"GND\g";
33"GND\g";
34"GND\g";
35"GND\g";
36"GND\g";
37"GND\g";
38"GND\g";
39"GND\g";
40"GND\g";
41"GND\g";
42"GND\g";
43"GND\g";
44"GND\g";
45"GND\g";
46"GND\g";
47"GND\g";
48"GND\g";
49"GND\g";
50"GND\g";
51"GND\g";
52"GND\g";
53"GND\g";
54"GND\g";
55"GND\g";
56"GND\g";
57"FM_SWB_PWRGD";
58"BIC_MONITER_ISO";
59"RST_BMC_FROM_SWB_ISO_N";
60"FM_GPU_PWRGD";
61"FM_SWB_BIC_READY_N";
62"FM_SWB_BIC_READY_ISO_N";
63"FM_SWB_BIC_READY";
64"FM_SMB_1_ALERT_GPU_N";
65"FM_SMB_2_ALERT_GPU_N";
66"GPU_FPGA_READY";
67"FM_SMB_1_ALERT_GPU_ISO_N";
68"RST_BMC_FROM_SWB_N";
69"BIC_MONITER";
70"RST_BMC_FROM_SWB";
71"GPU_FPGA_READY_ISO";
72"BIC_MONITER_N";
73"FM_SWB_PWRGD_N";
74"FM_SWB_PWRGD_ISO";
75"FM_GPU_PWRGD_ISO";
76"FM_SMB_2_ALERT_GPU_ISO_N";
77"FM_GPU_PWRGD_N";
78"FM_SMB_2_ALERT_GPU";
79"FM_SMB_1_ALERT_GPU";
80"GPU_FPGA_READY_N";
%"UNIVERSAL_GND"
"1","(-3525,7025)","0","logical_power","I10";
;
CDS_LIB"logical_power"
HDL_POWER"GND";
"A"48;
%"MOSFET_NCH_DUAL"
"2","(1875,7800)","0","pure_quanta","I100";
;
PART_NUMBER"BAM138K0003"
MATERIAL"IC"
VALUE"PJT138K"
PART_TYPE"SMLF"
LOCATION"Q71"
CDS_LMAN_SYM_OUTLINE"-150,150,150,-150"
NEEDS_NO_SIZE"TRUE"
CDS_LIB"pure_quanta"
$SEC"2"
CDS_SEC"2";
"S2"
$PN"4"38;
"G2"
$PN"5"73;
"D2"
$PN"3"74;
%"Q_RES"
"2","(1925,8175)","0","pure_quanta","I101";
;
PART_NUMBER"CS24702JB10"
TOLERANCE"5%"
VALUE"4.7K"
MATERIAL"CHIP"
WATTAGE"1/16W"
PACK_TYPE"0402LF"
$LOCATION"R2934"
CDS_LIB"pure_quanta"
CDS_LOCATION"R2934"
$SEC"1"
CDS_SEC"1";
"A"
$PN"1"4;
"B"
$PN"2"74;
%"UNIVERSAL_POWER"
"1","(1925,8475)","0","logical_power","I102";
;
HDL_POWER"P3V3_AUX"
CDS_LIB"logical_power";
"A"4;
%"UNIVERSAL_GND"
"1","(1925,7425)","0","logical_power","I103";
;
CDS_LIB"logical_power"
HDL_POWER"GND";
"A"38;
%"UNIVERSAL_GND"
"1","(2925,6050)","0","logical_power","I104";
;
HDL_POWER"GND"
CDS_LIB"logical_power";
"A"36;
%"Q_CAP"
"1","(2925,6250)","0","pure_quanta","I105";
;
PART_NUMBER"TMP_QCH21006JB10"
VALUE"1000PF"
MATERIAL"EMPTY"
TOLERANCE"5%"
PACK_TYPE"0402"
VOLTAGE"50V"
$LOCATION"C1756"
CDS_LIB"pure_quanta"
CDS_LOCATION"C1756"
$SEC"1"
CDS_SEC"1";
"B"
$PN"2"36;
"A"
$PN"1"75;
%"UNIVERSAL_GND"
"1","(2025,6050)","0","logical_power","I108";
;
HDL_POWER"GND"
CDS_LIB"logical_power";
"A"35;
%"Q_RES"
"2","(2025,6875)","0","pure_quanta","I109";
;
PART_NUMBER"CS24702JB10"
VALUE"4.7K"
TOLERANCE"5%"
MATERIAL"CHIP"
WATTAGE"1/16W"
PACK_TYPE"0402LF"
$LOCATION"R2935"
CDS_LIB"pure_quanta"
CDS_LOCATION"R2935"
$SEC"1"
CDS_SEC"1";
"A"
$PN"1"24;
"B"
$PN"2"75;
%"UNIVERSAL_GND"
"1","(-3475,5625)","0","logical_power","I11";
;
HDL_POWER"GND"
CDS_LIB"logical_power";
"A"43;
%"UNIVERSAL_POWER"
"1","(2025,7175)","0","logical_power","I110";
;
HDL_POWER"P3V3_AUX"
CDS_LIB"logical_power";
"A"24;
%"Q_CAP"
"1","(2875,7775)","0","pure_quanta","I111";
;
PART_NUMBER"TMP_QCH21006JB10"
MATERIAL"EMPTY"
VALUE"1000PF"
VOLTAGE"50V"
TOLERANCE"5%"
PACK_TYPE"0402"
$LOCATION"C1774"
CDS_LIB"pure_quanta"
CDS_LOCATION"C1774"
$SEC"1"
CDS_SEC"1";
"B"
$PN"2"39;
"A"
$PN"1"74;
%"UNIVERSAL_GND"
"1","(2875,7575)","0","logical_power","I112";
;
CDS_LIB"logical_power"
HDL_POWER"GND";
"A"39;
%"UNIVERSAL_GND"
"1","(-1600,7450)","0","logical_power","I113";
;
HDL_POWER"GND"
CDS_LIB"logical_power";
"A"46;
%"Q_CAP"
"1","(-1600,7650)","0","pure_quanta","I114";
;
PART_NUMBER"TMP_QCH21006JB10"
TOLERANCE"5%"
MATERIAL"EMPTY"
VOLTAGE"50V"
PACK_TYPE"0402"
VALUE"1000PF"
$LOCATION"C1773"
CDS_LIB"pure_quanta"
CDS_LOCATION"C1773"
$SEC"1"
CDS_SEC"1";
"B"
$PN"2"46;
"A"
$PN"1"58;
%"UNIVERSAL_GND"
"1","(-1650,6075)","0","logical_power","I115";
;
CDS_LIB"logical_power"
HDL_POWER"GND";
"A"45;
%"Q_CAP"
"1","(-1650,6275)","0","pure_quanta","I116";
;
PART_NUMBER"TMP_QCH21006JB10"
VALUE"1000PF"
MATERIAL"EMPTY"
PACK_TYPE"0402"
VOLTAGE"50V"
TOLERANCE"5%"
$LOCATION"C1772"
CDS_LIB"pure_quanta"
CDS_LOCATION"C1772"
$SEC"1"
CDS_SEC"1";
"B"
$PN"2"45;
"A"
$PN"1"59;
%"MOSFET_NCH_DUAL"
"1","(-3525,6000)","0","pure_quanta","I117";
;
PART_NUMBER"BAM138K0003"
VALUE"PJT138K"
MATERIAL"IC"
PART_TYPE"SMLF"
LOCATION"Q69"
CDS_LMAN_SYM_OUTLINE"-150,150,150,-150"
NEEDS_NO_SIZE"TRUE"
CDS_LIB"pure_quanta"
$SEC"1"
CDS_SEC"1";
"D1"
$PN"6"70;
"G1"
$PN"2"68;
"S1"
$PN"1"43;
%"MOSFET_NCH_DUAL"
"1","(1050,7525)","0","pure_quanta","I118";
;
PART_NUMBER"BAM138K0003"
MATERIAL"IC"
PART_TYPE"SMLF"
VALUE"PJT138K"
LOCATION"Q71"
CDS_LMAN_SYM_OUTLINE"-150,150,150,-150"
NEEDS_NO_SIZE"TRUE"
CDS_LIB"pure_quanta"
$SEC"1"
CDS_SEC"1";
"D1"
$PN"6"73;
"G1"
$PN"2"57;
"S1"
$PN"1"37;
%"MOSFET_NCH_DUAL"
"2","(1975,6425)","0","pure_quanta","I119";
;
PART_NUMBER"BAM138K0003"
MATERIAL"IC"
VALUE"PJT138K"
PART_TYPE"SMLF"
LOCATION"Q72"
CDS_LMAN_SYM_OUTLINE"-150,150,150,-150"
NEEDS_NO_SIZE"TRUE"
CDS_LIB"pure_quanta"
SEC_TYPE""
SEC"2";
"S2"
$PN"4"35;
"G2"
$PN"5"77;
"D2"
$PN"3"75;
%"UNIVERSAL_GND"
"1","(-3450,4275)","0","logical_power","I12";
;
HDL_POWER"GND"
CDS_LIB"logical_power";
"A"40;
%"MOSFET_NCH_DUAL"
"2","(-2550,4925)","0","pure_quanta","I120";
;
PART_NUMBER"BAM138K0003"
VALUE"PJT138K"
PART_TYPE"SMLF"
MATERIAL"IC"
LOCATION"Q70"
CDS_LMAN_SYM_OUTLINE"-150,150,150,-150"
NEEDS_NO_SIZE"TRUE"
CDS_LIB"pure_quanta"
$SEC"2"
CDS_SEC"2";
"S2"
$PN"4"41;
"G2"
$PN"5"63;
"D2"
$PN"3"62;
%"MOSFET_NCH_DUAL"
"1","(1075,4775)","0","pure_quanta","I121";
;
PART_NUMBER"BAM138K0003"
MATERIAL"IC"
PART_TYPE"SMLF"
VALUE"PJT138K"
LOCATION"Q74"
CDS_LMAN_SYM_OUTLINE"-150,150,150,-150"
NEEDS_NO_SIZE"TRUE"
CDS_LIB"pure_quanta"
SEC_TYPE""
SEC"1";
"D1"
$PN"6"78;
"G1"
$PN"2"65;
"S1"
$PN"1"31;
%"MOSFET_NCH_DUAL"
"2","(2000,5050)","0","pure_quanta","I122";
;
PART_NUMBER"BAM138K0003"
MATERIAL"IC"
VALUE"PJT138K"
PART_TYPE"SMLF"
LOCATION"Q74"
NEEDS_NO_SIZE"TRUE"
CDS_LMAN_SYM_OUTLINE"-150,150,150,-150"
CDS_LIB"pure_quanta"
SEC_TYPE""
SEC"2";
"S2"
$PN"4"33;
"G2"
$PN"5"78;
"D2"
$PN"3"76;
%"UNIVERSAL_POWER"
"1","(2050,5800)","0","logical_power","I123";
;
HDL_POWER"P3V3_AUX"
CDS_LIB"logical_power";
"A"10;
%"Q_CAP"
"1","(2950,4875)","0","pure_quanta","I125";
;
PART_NUMBER"TMP_QCH21006JB10"
TOLERANCE"5%"
VALUE"1000PF"
VOLTAGE"50V"
MATERIAL"EMPTY"
PACK_TYPE"0402"
$LOCATION"C1804"
CDS_LIB"pure_quanta"
CDS_LOCATION"C1804"
$SEC"1"
CDS_SEC"1";
"B"
$PN"2"32;
"A"
$PN"1"76;
%"UNIVERSAL_GND"
"1","(2950,4675)","0","logical_power","I126";
;
CDS_LIB"logical_power"
HDL_POWER"GND";
"A"32;
%"Q_RES"
"2","(2050,5500)","0","pure_quanta","I127";
;
PART_NUMBER"CS24702JB10"
PACK_TYPE"0402LF"
VALUE"4.7K"
TOLERANCE"5%"
MATERIAL"CHIP"
WATTAGE"1/16W"
$LOCATION"R3035"
CDS_LIB"pure_quanta"
CDS_LOCATION"R3035"
$SEC"1"
CDS_SEC"1";
"A"
$PN"1"10;
"B"
$PN"2"76;
%"UNIVERSAL_POWER"
"1","(1125,5550)","0","logical_power","I128";
;
HDL_POWER"P3V3_AUX"
CDS_LIB"logical_power";
"A"9;
%"Q_RES"
"2","(1125,5250)","0","pure_quanta","I129";
;
PART_NUMBER"CS24702JB10"
TOLERANCE"5%"
VALUE"4.7K"
WATTAGE"1/16W"
MATERIAL"CHIP"
PACK_TYPE"0402LF"
$LOCATION"R3034"
CDS_LIB"pure_quanta"
CDS_LOCATION"R3034"
$SEC"1"
CDS_SEC"1";
"A"
$PN"1"9;
"B"
$PN"2"78;
%"UNIVERSAL_POWER"
"1","(-3525,8225)","0","logical_power","I13";
;
HDL_POWER"P3V3_AUX"
CDS_LIB"logical_power";
"A"7;
%"UNIVERSAL_GND"
"1","(2050,4675)","0","logical_power","I130";
;
CDS_LIB"logical_power"
HDL_POWER"GND";
"A"33;
%"UNIVERSAL_GND"
"1","(1125,4400)","0","logical_power","I131";
;
CDS_LIB"logical_power"
HDL_POWER"GND";
"A"31;
%"UNIVERSAL_POWER"
"1","(-125,5250)","0","logical_power","I132";
;
HDL_POWER"P3V3_AUX"
CDS_LIB"logical_power";
"A"11;
%"Q_RES"
"2","(-100,4525)","0","pure_quanta","I134";
;
PART_NUMBER"CS41002FB09"
PACK_TYPE"0402LF"
MATERIAL"EMPTY"
WATTAGE"1/16W"
TOLERANCE"1%"
VALUE"100K"
$LOCATION"R3032"
CDS_LIB"pure_quanta"
CDS_LOCATION"R3032"
$SEC"1"
CDS_SEC"1";
"A"
$PN"1"65;
"B"
$PN"2"54;
%"UNIVERSAL_GND"
"1","(-100,4325)","0","logical_power","I135";
;
CDS_LIB"logical_power"
HDL_POWER"GND";
"A"54;
%"UNIVERSAL_GND"
"1","(-4650,2625)","0","logical_power","I138";
;
CDS_LIB"logical_power"
HDL_POWER"GND";
"A"52;
%"Q_RES"
"2","(-4650,2825)","0","pure_quanta","I139";
;
PART_NUMBER"CS41002FB09"
WATTAGE"1/16W"
VALUE"100K"
MATERIAL"EMPTY"
TOLERANCE"1%"
PACK_TYPE"0402LF"
$LOCATION"R3028"
CDS_LIB"pure_quanta"
CDS_LOCATION"R3028"
$SEC"1"
CDS_SEC"1";
"A"
$PN"1"64;
"B"
$PN"2"52;
%"Q_RES"
"2","(-3525,8000)","0","pure_quanta","I14";
;
PART_NUMBER"CS24702JB10"
PACK_TYPE"0402LF"
VALUE"4.7K"
TOLERANCE"5%"
WATTAGE"1/16W"
MATERIAL"CHIP"
$LOCATION"R2835"
CDS_LIB"pure_quanta"
CDS_LOCATION"R2835"
$SEC"1"
CDS_SEC"1";
"A"
$PN"1"7;
"B"
$PN"2"72;
%"UNIVERSAL_POWER"
"1","(-4675,3550)","0","logical_power","I141";
;
HDL_POWER"P3V3_AUX"
CDS_LIB"logical_power";
"A"21;
%"UNIVERSAL_GND"
"1","(-3425,2700)","0","logical_power","I142";
;
HDL_POWER"GND"
CDS_LIB"logical_power";
"A"28;
%"UNIVERSAL_GND"
"1","(-2500,2975)","0","logical_power","I143";
;
CDS_LIB"logical_power"
HDL_POWER"GND";
"A"29;
%"Q_RES"
"2","(-3425,3550)","0","pure_quanta","I144";
;
PART_NUMBER"CS24702JB10"
VALUE"4.7K"
PACK_TYPE"0402LF"
WATTAGE"1/16W"
MATERIAL"CHIP"
TOLERANCE"5%"
$LOCATION"R3029"
CDS_LIB"pure_quanta"
CDS_LOCATION"R3029"
$SEC"1"
CDS_SEC"1";
"A"
$PN"1"22;
"B"
$PN"2"79;
%"UNIVERSAL_POWER"
"1","(-3425,3850)","0","logical_power","I145";
;
HDL_POWER"P3V3_AUX"
CDS_LIB"logical_power";
"A"22;
%"Q_RES"
"2","(-2500,3800)","0","pure_quanta","I146";
;
PART_NUMBER"CS24702JB10"
VALUE"4.7K"
WATTAGE"1/16W"
PACK_TYPE"0402LF"
MATERIAL"CHIP"
TOLERANCE"5%"
$LOCATION"R3030"
CDS_LIB"pure_quanta"
CDS_LOCATION"R3030"
$SEC"1"
CDS_SEC"1";
"A"
$PN"1"23;
"B"
$PN"2"67;
%"UNIVERSAL_GND"
"1","(-1600,2975)","0","logical_power","I147";
;
CDS_LIB"logical_power"
HDL_POWER"GND";
"A"30;
%"Q_CAP"
"1","(-1600,3175)","0","pure_quanta","I148";
;
PART_NUMBER"TMP_QCH21006JB10"
VALUE"1000PF"
VOLTAGE"50V"
PACK_TYPE"0402"
TOLERANCE"5%"
MATERIAL"EMPTY"
$LOCATION"C1802"
CDS_LIB"pure_quanta"
CDS_LOCATION"C1802"
$SEC"1"
CDS_SEC"1";
"B"
$PN"2"30;
"A"
$PN"1"67;
%"UNIVERSAL_POWER"
"1","(-2500,4100)","0","logical_power","I150";
;
HDL_POWER"P3V3_AUX"
CDS_LIB"logical_power";
"A"23;
%"MOSFET_NCH_DUAL"
"2","(-2550,3350)","0","pure_quanta","I151";
;
PART_NUMBER"BAM138K0003"
VALUE"PJT138K"
MATERIAL"IC"
PART_TYPE"SMLF"
LOCATION"Q75"
CDS_LIB"pure_quanta"
NEEDS_NO_SIZE"TRUE"
CDS_LMAN_SYM_OUTLINE"-150,150,150,-150"
$SEC"2"
CDS_SEC"2";
"S2"
$PN"4"29;
"G2"
$PN"5"79;
"D2"
$PN"3"67;
%"MOSFET_NCH_DUAL"
"1","(-3475,3075)","0","pure_quanta","I152";
;
PART_NUMBER"BAM138K0003"
VALUE"PJT138K"
PART_TYPE"SMLF"
MATERIAL"IC"
LOCATION"Q75"
CDS_LIB"pure_quanta"
NEEDS_NO_SIZE"TRUE"
CDS_LMAN_SYM_OUTLINE"-150,150,150,-150"
$SEC"1"
CDS_SEC"1";
"D1"
$PN"6"79;
"G1"
$PN"2"64;
"S1"
$PN"1"28;
%"UNIVERSAL_POWER"
"1","(2000,4250)","0","logical_power","I153";
;
HDL_POWER"P3V3_AUX"
CDS_LIB"logical_power";
"A"15;
%"MOSFET_NCH_DUAL"
"1","(1025,3225)","0","pure_quanta","I154";
;
PART_NUMBER"BAM138K0003"
MATERIAL"IC"
VALUE"PJT138K"
PART_TYPE"SMLF"
$LOCATION"Q96"
CDS_LMAN_SYM_OUTLINE"-150,150,150,-150"
NEEDS_NO_SIZE"TRUE"
CDS_LIB"pure_quanta"
CDS_LOCATION"Q96"
$SEC"1"
CDS_SEC"1";
"D1"
$PN"6"80;
"G1"
$PN"2"66;
"S1"
$PN"1"27;
%"Q_CAP"
"1","(2900,3325)","0","pure_quanta","I156";
;
PART_NUMBER"TMP_QCH21006JB10"
TOLERANCE"5%"
VALUE"1000PF"
MATERIAL"EMPTY"
VOLTAGE"50V"
PACK_TYPE"0402"
$LOCATION"C1881"
CDS_LIB"pure_quanta"
CDS_LOCATION"C1881"
$SEC"1"
CDS_SEC"1";
"B"
$PN"2"25;
"A"
$PN"1"71;
%"UNIVERSAL_GND"
"1","(2900,3125)","0","logical_power","I157";
;
HDL_POWER"GND"
CDS_LIB"logical_power";
"A"25;
%"Q_RES"
"2","(2000,3950)","0","pure_quanta","I158";
;
PART_NUMBER"CS24702JB10"
PACK_TYPE"0402LF"
WATTAGE"1/16W"
TOLERANCE"5%"
VALUE"4.7K"
MATERIAL"CHIP"
$LOCATION"R3321"
CDS_LIB"pure_quanta"
CDS_LOCATION"R3321"
$SEC"1"
CDS_SEC"1";
"A"
$PN"1"15;
"B"
$PN"2"71;
%"MOSFET_NCH_DUAL"
"2","(1950,3500)","0","pure_quanta","I159";
;
PART_NUMBER"BAM138K0003"
PART_TYPE"SMLF"
VALUE"PJT138K"
MATERIAL"IC"
LOCATION"Q96"
CDS_LMAN_SYM_OUTLINE"-150,150,150,-150"
NEEDS_NO_SIZE"TRUE"
CDS_LIB"pure_quanta"
$SEC"2"
CDS_SEC"2";
"S2"
$PN"4"26;
"G2"
$PN"5"80;
"D2"
$PN"3"71;
%"UNIVERSAL_POWER"
"1","(-3475,6750)","0","logical_power","I16";
;
HDL_POWER"P3V3_AUX"
CDS_LIB"logical_power";
"A"5;
%"UNIVERSAL_GND"
"1","(2000,3125)","0","logical_power","I160";
;
HDL_POWER"GND"
CDS_LIB"logical_power";
"A"26;
%"UNIVERSAL_POWER"
"1","(1075,4000)","0","logical_power","I161";
;
HDL_POWER"P3V3_AUX"
CDS_LIB"logical_power";
"A"14;
%"Q_RES"
"2","(1075,3700)","0","pure_quanta","I162";
;
PART_NUMBER"CS24702JB10"
TOLERANCE"5%"
PACK_TYPE"0402LF"
VALUE"4.7K"
MATERIAL"CHIP"
WATTAGE"1/16W"
$LOCATION"R3320"
CDS_LIB"pure_quanta"
CDS_LOCATION"R3320"
$SEC"1"
CDS_SEC"1";
"A"
$PN"1"14;
"B"
$PN"2"80;
%"UNIVERSAL_GND"
"1","(1075,2850)","0","logical_power","I163";
;
CDS_LIB"logical_power"
HDL_POWER"GND";
"A"27;
%"UNIVERSAL_POWER"
"1","(-175,3700)","0","logical_power","I164";
;
HDL_POWER"P3V3_AUX"
CDS_LIB"logical_power";
"A"13;
%"UNIVERSAL_GND"
"1","(-150,2775)","0","logical_power","I167";
;
HDL_POWER"GND"
CDS_LIB"logical_power";
"A"53;
%"Q_RES"
"2","(-175,3400)","0","pure_quanta","I171";
;
PART_NUMBER"CS41002FB09"
PACK_TYPE"0402LF"
WATTAGE"1/16W"
TOLERANCE"1%"
MATERIAL"EMPTY"
VALUE"100K"
$LOCATION"R3318"
CDS_LIB"pure_quanta"
CDS_LOCATION"R3318"
$SEC"1"
CDS_SEC"1";
"A"
$PN"1"13;
"B"
$PN"2"66;
%"Q_RES"
"2","(-150,2975)","0","pure_quanta","I172";
;
PART_NUMBER"CS35492FB03"
TOLERANCE"1%"
WATTAGE"1/16W"
PACK_TYPE"0402LF"
MATERIAL"CHIP"
VALUE"54.9K"
$LOCATION"R3511"
CDS_LIB"pure_quanta"
CDS_LOCATION"R3511"
$SEC"1"
CDS_SEC"1";
"A"
$PN"1"66;
"B"
$PN"2"53;
%"Q_RES"
"2","(-125,5900)","0","pure_quanta","I173";
;
PART_NUMBER"CS35492FB03"
VALUE"54.9K"
TOLERANCE"1%"
WATTAGE"1/16W"
MATERIAL"CHIP"
PACK_TYPE"0402LF"
$LOCATION"R3513"
CDS_LIB"pure_quanta"
CDS_LOCATION"R3513"
$SEC"1"
CDS_SEC"1";
"A"
$PN"1"60;
"B"
$PN"2"55;
%"Q_RES"
"2","(-150,6325)","0","pure_quanta","I174";
;
PART_NUMBER"CS41002FB09"
WATTAGE"1/16W"
PACK_TYPE"0402LF"
MATERIAL"EMPTY"
VALUE"100K"
TOLERANCE"1%"
$LOCATION"R3512"
CDS_LIB"pure_quanta"
CDS_LOCATION"R3512"
$SEC"1"
CDS_SEC"1";
"A"
$PN"1"12;
"B"
$PN"2"60;
%"Q_RES"
"2","(-125,4950)","0","pure_quanta","I175";
;
PART_NUMBER"CS35492FB03"
TOLERANCE"1%"
VALUE"54.9K"
WATTAGE"1/16W"
MATERIAL"CHIP"
PACK_TYPE"0402LF"
$LOCATION"R3514"
CDS_LIB"pure_quanta"
CDS_LOCATION"R3514"
$SEC"1"
CDS_SEC"1";
"A"
$PN"1"11;
"B"
$PN"2"65;
%"Q_RES"
"2","(-4675,3250)","0","pure_quanta","I176";
;
PART_NUMBER"CS35492FB03"
PACK_TYPE"0402LF"
MATERIAL"CHIP"
WATTAGE"1/16W"
VALUE"54.9K"
TOLERANCE"1%"
$LOCATION"R3510"
CDS_LIB"pure_quanta"
CDS_LOCATION"R3510"
$SEC"1"
CDS_SEC"1";
"A"
$PN"1"21;
"B"
$PN"2"64;
%"Q_RES"
"2","(-3475,6450)","0","pure_quanta","I18";
;
PART_NUMBER"CS24702JB10"
MATERIAL"CHIP"
VALUE"4.7K"
PACK_TYPE"0402LF"
TOLERANCE"5%"
WATTAGE"1/16W"
$LOCATION"R2834"
CDS_LIB"pure_quanta"
CDS_LOCATION"R2834"
$SEC"1"
CDS_SEC"1";
"A"
$PN"1"5;
"B"
$PN"2"70;
%"Q_RES"
"2","(-3450,5100)","0","pure_quanta","I19";
;
PART_NUMBER"CS24702JB10"
PACK_TYPE"0402LF"
MATERIAL"CHIP"
WATTAGE"1/16W"
TOLERANCE"5%"
VALUE"4.7K"
$LOCATION"R2836"
CDS_LIB"pure_quanta"
CDS_LOCATION"R2836"
$SEC"1"
CDS_SEC"1";
"A"
$PN"1"19;
"B"
$PN"2"63;
%"UNIVERSAL_POWER"
"1","(-3450,5400)","0","logical_power","I21";
;
HDL_POWER"P3V3_AUX"
CDS_LIB"logical_power";
"A"19;
%"UNIVERSAL_GND"
"1","(1100,7150)","0","logical_power","I23";
;
HDL_POWER"GND"
CDS_LIB"logical_power";
"A"37;
%"Q_RES"
"2","(1100,7925)","0","pure_quanta","I24";
;
PART_NUMBER"CS24702JB10"
PACK_TYPE"0402LF"
WATTAGE"1/16W"
MATERIAL"CHIP"
TOLERANCE"5%"
VALUE"4.7K"
$LOCATION"R2841"
CDS_LIB"pure_quanta"
CDS_LOCATION"R2841"
$SEC"1"
CDS_SEC"1";
"A"
$PN"1"2;
"B"
$PN"2"73;
%"UNIVERSAL_POWER"
"1","(1100,8225)","0","logical_power","I25";
;
HDL_POWER"P3V3_AUX"
CDS_LIB"logical_power";
"A"2;
%"UNIVERSAL_GND"
"1","(1100,5775)","0","logical_power","I29";
;
CDS_LIB"logical_power"
HDL_POWER"GND";
"A"34;
%"Q_RES"
"2","(1100,6625)","0","pure_quanta","I30";
;
PART_NUMBER"CS24702JB10"
WATTAGE"1/16W"
MATERIAL"CHIP"
PACK_TYPE"0402LF"
TOLERANCE"5%"
VALUE"4.7K"
$LOCATION"R2842"
CDS_LIB"pure_quanta"
CDS_LOCATION"R2842"
$SEC"1"
CDS_SEC"1";
"A"
$PN"1"3;
"B"
$PN"2"77;
%"UNIVERSAL_POWER"
"1","(1100,6925)","0","logical_power","I31";
;
HDL_POWER"P3V3_AUX"
CDS_LIB"logical_power";
"A"3;
%"MOSFET_NCH_DUAL"
"1","(-3575,7400)","0","pure_quanta","I33";
;
PART_NUMBER"BAM138K0003"
VALUE"PJT138K"
MATERIAL"IC"
PART_TYPE"SMLF"
$LOCATION"Q67"
CDS_LMAN_SYM_OUTLINE"-150,150,150,-150"
NEEDS_NO_SIZE"TRUE"
CDS_LIB"pure_quanta"
CDS_LOCATION"Q67"
$SEC"1"
CDS_SEC"1";
"D1"
$PN"6"72;
"G1"
$PN"2"69;
"S1"
$PN"1"48;
%"MOSFET_NCH_DUAL"
"1","(-3500,4650)","0","pure_quanta","I35";
;
PART_NUMBER"BAM138K0003"
PART_TYPE"SMLF"
VALUE"PJT138K"
MATERIAL"IC"
LOCATION"Q70"
CDS_LMAN_SYM_OUTLINE"-150,150,150,-150"
NEEDS_NO_SIZE"TRUE"
CDS_LIB"pure_quanta"
$SEC"1"
CDS_SEC"1";
"D1"
$PN"6"63;
"G1"
$PN"2"61;
"S1"
$PN"1"40;
%"MOSFET_NCH_DUAL"
"1","(1050,6150)","0","pure_quanta","I37";
;
PART_NUMBER"BAM138K0003"
PART_TYPE"SMLF"
VALUE"PJT138K"
MATERIAL"IC"
LOCATION"Q72"
CDS_LMAN_SYM_OUTLINE"-150,150,150,-150"
NEEDS_NO_SIZE"TRUE"
CDS_LIB"pure_quanta"
$SEC"1"
CDS_SEC"1";
"D1"
$PN"6"77;
"G1"
$PN"2"60;
"S1"
$PN"1"34;
%"UNIVERSAL_POWER"
"1","(-4700,7875)","0","logical_power","I46";
;
HDL_POWER"P3V3_AUX"
CDS_LIB"logical_power";
"A"8;
%"UNIVERSAL_POWER"
"1","(-4675,6475)","0","logical_power","I47";
;
HDL_POWER"P3V3_AUX"
CDS_LIB"logical_power";
"A"17;
%"UNIVERSAL_POWER"
"1","(-4625,5125)","0","logical_power","I49";
;
HDL_POWER"P3V3_AUX"
CDS_LIB"logical_power";
"A"20;
%"UNIVERSAL_POWER"
"1","(-150,8000)","0","logical_power","I51";
;
HDL_POWER"P3V3_AUX"
CDS_LIB"logical_power";
"A"1;
%"UNIVERSAL_POWER"
"1","(-150,6625)","0","logical_power","I53";
;
HDL_POWER"P3V3_AUX"
CDS_LIB"logical_power";
"A"12;
%"UNIVERSAL_GND"
"1","(-4675,6950)","0","logical_power","I55";
;
CDS_LIB"logical_power"
HDL_POWER"GND";
"A"49;
%"Q_RES"
"2","(-4675,7150)","0","pure_quanta","I56";
;
PART_NUMBER"CS41002FB09"
VALUE"100K"
TOLERANCE"1%"
MATERIAL"EMPTY"
WATTAGE"1/16W"
PACK_TYPE"0402LF"
$LOCATION"R2831"
CDS_LIB"pure_quanta"
CDS_LOCATION"R2831"
$SEC"1"
CDS_SEC"1";
"A"
$PN"1"69;
"B"
$PN"2"49;
%"UNIVERSAL_GND"
"1","(-4650,5575)","0","logical_power","I57";
;
CDS_LIB"logical_power"
HDL_POWER"GND";
"A"50;
%"Q_RES"
"2","(-4650,5750)","0","pure_quanta","I58";
;
PART_NUMBER"CS41002FB09"
WATTAGE"1/16W"
MATERIAL"EMPTY"
PACK_TYPE"0402LF"
TOLERANCE"1%"
VALUE"100K"
$LOCATION"R2829"
CDS_LIB"pure_quanta"
CDS_LOCATION"R2829"
$SEC"1"
CDS_SEC"1";
"A"
$PN"1"68;
"B"
$PN"2"50;
%"UNIVERSAL_GND"
"1","(-4600,4225)","0","logical_power","I59";
;
HDL_POWER"GND"
CDS_LIB"logical_power";
"A"51;
%"Q_RES"
"2","(-4600,4400)","0","pure_quanta","I60";
;
PART_NUMBER"CS41002FB09"
PACK_TYPE"0402LF"
MATERIAL"EMPTY"
WATTAGE"1/16W"
TOLERANCE"1%"
VALUE"100K"
$LOCATION"R2833"
CDS_LIB"pure_quanta"
CDS_LOCATION"R2833"
$SEC"1"
CDS_SEC"1";
"A"
$PN"1"61;
"B"
$PN"2"51;
%"UNIVERSAL_GND"
"1","(-125,7100)","0","logical_power","I61";
;
HDL_POWER"GND"
CDS_LIB"logical_power";
"A"56;
%"Q_RES"
"2","(-125,7275)","0","pure_quanta","I62";
;
PART_NUMBER"CS41002FB09"
MATERIAL"CHIP"
WATTAGE"1/16W"
TOLERANCE"1%"
VALUE"100K"
PACK_TYPE"0402LF"
$LOCATION"R2838"
CDS_LIB"pure_quanta"
CDS_LOCATION"R2838"
$SEC"1"
CDS_SEC"1";
"A"
$PN"1"57;
"B"
$PN"2"56;
%"UNIVERSAL_GND"
"1","(-125,5700)","0","logical_power","I63";
;
HDL_POWER"GND"
CDS_LIB"logical_power";
"A"55;
%"Q_RES"
"2","(-4675,6225)","0","pure_quanta","I66";
;
PART_NUMBER"CS41002FB09"
PACK_TYPE"0402LF"
WATTAGE"1/16W"
TOLERANCE"1%"
MATERIAL"CHIP"
VALUE"100K"
$LOCATION"R2828"
CDS_LIB"pure_quanta"
CDS_LOCATION"R2828"
$SEC"1"
CDS_SEC"1";
"A"
$PN"1"17;
"B"
$PN"2"68;
%"Q_RES"
"2","(-4625,4875)","0","pure_quanta","I67";
;
PART_NUMBER"CS41002FB09"
MATERIAL"CHIP"
PACK_TYPE"0402LF"
VALUE"100K"
TOLERANCE"1%"
WATTAGE"1/16W"
$LOCATION"R2832"
CDS_LIB"pure_quanta"
CDS_LOCATION"R2832"
$SEC"1"
CDS_SEC"1";
"A"
$PN"1"20;
"B"
$PN"2"61;
%"Q_RES"
"2","(-4700,7625)","0","pure_quanta","I68";
;
PART_NUMBER"CS41002FB09"
PACK_TYPE"0402LF"
MATERIAL"CHIP"
WATTAGE"1/16W"
TOLERANCE"1%"
VALUE"100K"
$LOCATION"R2830"
CDS_LIB"pure_quanta"
CDS_LOCATION"R2830"
$SEC"1"
CDS_SEC"1";
"A"
$PN"1"8;
"B"
$PN"2"69;
%"Q_RES"
"2","(-150,7700)","0","pure_quanta","I80";
;
PART_NUMBER"CS41002FB09"
PACK_TYPE"0402LF"
MATERIAL"EMPTY"
WATTAGE"1/16W"
VALUE"100K"
TOLERANCE"1%"
$LOCATION"R2837"
CDS_LIB"pure_quanta"
CDS_LOCATION"R2837"
$SEC"1"
CDS_SEC"1";
"A"
$PN"1"1;
"B"
$PN"2"57;
%"MOSFET_NCH_DUAL"
"2","(-2425,7700)","0","pure_quanta","I82";
;
PART_NUMBER"BAM138K0003"
VALUE"PJT138K"
PART_TYPE"SMLF"
MATERIAL"IC"
LOCATION"Q67"
CDS_LMAN_SYM_OUTLINE"-150,150,150,-150"
NEEDS_NO_SIZE"TRUE"
CDS_LIB"pure_quanta"
$SEC"2"
CDS_SEC"2";
"S2"
$PN"4"47;
"G2"
$PN"5"72;
"D2"
$PN"3"58;
%"UNIVERSAL_GND"
"1","(-2375,7325)","0","logical_power","I83";
;
CDS_LIB"logical_power"
HDL_POWER"GND";
"A"47;
%"Q_RES"
"2","(-2375,8125)","0","pure_quanta","I84";
;
PART_NUMBER"CS24702JB10"
PACK_TYPE"0402LF"
MATERIAL"CHIP"
WATTAGE"1/16W"
VALUE"4.7K"
TOLERANCE"5%"
$LOCATION"R2920"
CDS_LIB"pure_quanta"
CDS_LOCATION"R2920"
$SEC"1"
CDS_SEC"1";
"A"
$PN"1"6;
"B"
$PN"2"58;
%"UNIVERSAL_POWER"
"1","(-2375,8350)","0","logical_power","I85";
;
HDL_POWER"P3V3_AUX"
CDS_LIB"logical_power";
"A"6;
%"MOSFET_NCH_DUAL"
"2","(-2525,6300)","0","pure_quanta","I88";
;
PART_NUMBER"BAM138K0003"
VALUE"PJT138K"
PART_TYPE"SMLF"
MATERIAL"IC"
LOCATION"Q69"
CDS_LMAN_SYM_OUTLINE"-150,150,150,-150"
NEEDS_NO_SIZE"TRUE"
CDS_LIB"pure_quanta"
$SEC"2"
CDS_SEC"2";
"S2"
$PN"4"44;
"G2"
$PN"5"70;
"D2"
$PN"3"59;
%"UNIVERSAL_GND"
"1","(-2475,5925)","0","logical_power","I89";
;
CDS_LIB"logical_power"
HDL_POWER"GND";
"A"44;
%"UNIVERSAL_POWER"
"1","(-2475,6950)","0","logical_power","I90";
;
HDL_POWER"P3V3_AUX"
CDS_LIB"logical_power";
"A"18;
%"Q_RES"
"2","(-2475,6725)","0","pure_quanta","I91";
;
PART_NUMBER"CS24702JB10"
WATTAGE"1/16W"
TOLERANCE"5%"
MATERIAL"CHIP"
PACK_TYPE"0402LF"
VALUE"4.7K"
$LOCATION"R2919"
CDS_LIB"pure_quanta"
CDS_LOCATION"R2919"
$SEC"1"
CDS_SEC"1";
"A"
$PN"1"18;
"B"
$PN"2"59;
%"Q_CAP"
"1","(-1600,4925)","0","pure_quanta","I92";
;
PART_NUMBER"TMP_QCH21006JB10"
VOLTAGE"50V"
MATERIAL"EMPTY"
PACK_TYPE"0402"
TOLERANCE"5%"
VALUE"1000PF"
$LOCATION"C1754"
CDS_LIB"pure_quanta"
CDS_LOCATION"C1754"
$SEC"1"
CDS_SEC"1";
"B"
$PN"2"42;
"A"
$PN"1"62;
%"UNIVERSAL_GND"
"1","(-1600,4725)","0","logical_power","I93";
;
CDS_LIB"logical_power"
HDL_POWER"GND";
"A"42;
%"UNIVERSAL_GND"
"1","(-2500,4550)","0","logical_power","I96";
;
CDS_LIB"logical_power"
HDL_POWER"GND";
"A"41;
%"Q_RES"
"2","(-2500,5350)","0","pure_quanta","I97";
;
PART_NUMBER"CS24702JB10"
PACK_TYPE"0402LF"
WATTAGE"1/16W"
MATERIAL"CHIP"
VALUE"4.7K"
TOLERANCE"5%"
$LOCATION"R2933"
CDS_LIB"pure_quanta"
CDS_LOCATION"R2933"
$SEC"1"
CDS_SEC"1";
"A"
$PN"1"16;
"B"
$PN"2"62;
%"UNIVERSAL_POWER"
"1","(-2500,5650)","0","logical_power","I98";
;
HDL_POWER"P3V3_AUX"
CDS_LIB"logical_power";
"A"16;
END.
